(kicad_pcb
	(version 20260206)
	(generator "pcbnew")
	(generator_version "10.0")
	(general
		(thickness 1.6)
		(legacy_teardrops no)
	)
	(paper "A4")
	(title_block
		(title "15969-1a.1015WZS0858.brd")
		(comment 1 "Tioga Pass / footprints 27-34 of 295")
	)
	(layers
		(0 "F.Cu" signal "TOP")
		(4 "In1.Cu" signal "L2GND")
		(6 "In2.Cu" signal "L3")
		(8 "In3.Cu" signal "L4")
		(10 "In4.Cu" signal "L5GND")
		(2 "B.Cu" signal "BOTTOM")
		(9 "F.Adhes" user "F.Adhesive")
		(11 "B.Adhes" user "B.Adhesive")
		(13 "F.Paste" user "Package Geometry/Pastemask Top")
		(15 "B.Paste" user "Package Geometry/Pastemask Bottom")
		(5 "F.SilkS" user "Ref Des/Silkscreen Top")
		(7 "B.SilkS" user "Ref Des/Silkscreen Bottom")
		(1 "F.Mask" user "Board Geometry/Soldermask Top")
		(3 "B.Mask" user "Board Geometry/Soldermask Bottom")
		(17 "Dwgs.User" user "User.Drawings")
		(19 "Cmts.User" user "User.Comments")
		(21 "Eco1.User" user "User.Eco1")
		(23 "Eco2.User" user "User.Eco2")
		(25 "Edge.Cuts" user "Board Geometry/Outline")
		(27 "Margin" user)
		(31 "F.CrtYd" user "Package Geometry/Place Bound Top")
		(29 "B.CrtYd" user "Package Geometry/Place Bound Bottom")
		(35 "F.Fab" user "Ref Des/Assembly Top")
		(33 "B.Fab" user "Ref Des/Assembly Bottom")
	)
	(footprint ""
		(layer "F.Cu")
		(at 119.5832 -7.0358 -90)
		(property "Reference" "R137"
			(at 0 0 270)
			(layer "F.SilkS")
			(hide yes)
			(effects
				(font
					(size 1.27 1.27)
				)
			)
		)
		(property "Value" "10KR2F-2-GP"
			(at 0.064008 -3.993896 270)
			(unlocked yes)
			(layer "F.Fab")
			(hide yes)
			(effects
				(font
					(size 1.016 1.016)
					(thickness 0.1524)
				)
			)
		)
		(property "Device Type" "R402H16"
			(at 0.064008 -5.517896 270)
			(unlocked yes)
			(layer "F.Fab")
			(hide yes)
			(effects
				(font
					(size 1.016 1.016)
					(thickness 0.1524)
				)
			)
		)
		(duplicate_pad_numbers_are_jumpers no)
		(fp_line
			(start -0.508 -0.9398)
			(end -0.508 0.9398)
			(stroke
				(width 0.1524)
				(type default)
			)
			(layer "F.SilkS")
		)
		(fp_line
			(start 0.508 -0.9398)
			(end -0.508 -0.9398)
			(stroke
				(width 0.1524)
				(type default)
			)
			(layer "F.SilkS")
		)
		(fp_rect
			(start -0.508 0.9398)
			(end 0.508 -0.9398)
			(stroke
				(width 0)
				(type default)
			)
			(fill no)
			(layer "F.CrtYd")
		)
		(fp_rect
			(start -0.508 0.9398)
			(end 0.508 -0.9398)
			(stroke
				(width 0)
				(type default)
			)
			(fill no)
			(layer "F.Fab")
		)
		(pad "1" smd custom
			(at 0 -0.4445 270)
			(size 0.1397 0.1397)
			(layers "F.Cu" "F.Mask" "F.Paste")
			(net "GPIO_P_IO1_3")
			(options
				(clearance outline)
				(anchor circle)
			)
			(primitives
				(gr_poly
					(pts
						(arc
							(start -0.1778 -0.2794)
							(mid -0.249642 -0.249642)
							(end -0.2794 -0.1778)
						)
						(arc
							(start -0.2794 0.1778)
							(mid -0.249642 0.249642)
							(end -0.1778 0.2794)
						)
						(arc
							(start 0.1778 0.2794)
							(mid 0.249642 0.249642)
							(end 0.2794 0.1778)
						)
						(arc
							(start 0.2794 -0.1778)
							(mid 0.249642 -0.249642)
							(end 0.1778 -0.2794)
						)
					)
					(width 0)
					(fill yes)
				)
			)
		)
		(pad "2" smd custom
			(at 0 0.4445 270)
			(size 0.1397 0.1397)
			(layers "F.Cu" "F.Mask" "F.Paste")
			(net "GND")
			(options
				(clearance outline)
				(anchor circle)
			)
			(primitives
				(gr_poly
					(pts
						(arc
							(start -0.1778 -0.2794)
							(mid -0.249642 -0.249642)
							(end -0.2794 -0.1778)
						)
						(arc
							(start -0.2794 0.1778)
							(mid -0.249642 0.249642)
							(end -0.1778 0.2794)
						)
						(arc
							(start 0.1778 0.2794)
							(mid 0.249642 0.249642)
							(end 0.2794 0.1778)
						)
						(arc
							(start 0.2794 -0.1778)
							(mid 0.249642 -0.249642)
							(end 0.1778 -0.2794)
						)
					)
					(width 0)
					(fill yes)
				)
			)
		)
	)
	(footprint ""
		(layer "F.Cu")
		(at 109.1946 0.2794)
		(property "Reference" "R12"
			(at 0 0 0)
			(layer "F.SilkS")
			(hide yes)
			(effects
				(font
					(size 1.27 1.27)
				)
			)
		)
		(property "Value" "10KR2F-2-GP"
			(at 0.064008 -3.993896 0)
			(unlocked yes)
			(layer "F.Fab")
			(hide yes)
			(effects
				(font
					(size 1.016 1.016)
					(thickness 0.1524)
				)
			)
		)
		(property "Device Type" "R402H16"
			(at 0.064008 -5.517896 0)
			(unlocked yes)
			(layer "F.Fab")
			(hide yes)
			(effects
				(font
					(size 1.016 1.016)
					(thickness 0.1524)
				)
			)
		)
		(duplicate_pad_numbers_are_jumpers no)
		(fp_line
			(start -0.508 -0.9398)
			(end -0.508 0.9398)
			(stroke
				(width 0.1524)
				(type default)
			)
			(layer "F.SilkS")
		)
		(fp_line
			(start 0.508 -0.9398)
			(end -0.508 -0.9398)
			(stroke
				(width 0.1524)
				(type default)
			)
			(layer "F.SilkS")
		)
		(fp_rect
			(start -0.508 0.9398)
			(end 0.508 -0.9398)
			(stroke
				(width 0)
				(type default)
			)
			(fill no)
			(layer "F.CrtYd")
		)
		(fp_rect
			(start -0.508 0.9398)
			(end 0.508 -0.9398)
			(stroke
				(width 0)
				(type default)
			)
			(fill no)
			(layer "F.Fab")
		)
		(pad "1" smd custom
			(at 0 -0.4445)
			(size 0.1397 0.1397)
			(layers "F.Cu" "F.Mask" "F.Paste")
			(net "P3V3_STBY")
			(options
				(clearance outline)
				(anchor circle)
			)
			(primitives
				(gr_poly
					(pts
						(arc
							(start -0.1778 -0.2794)
							(mid -0.249642 -0.249642)
							(end -0.2794 -0.1778)
						)
						(arc
							(start -0.2794 0.1778)
							(mid -0.249642 0.249642)
							(end -0.1778 0.2794)
						)
						(arc
							(start 0.1778 0.2794)
							(mid 0.249642 0.249642)
							(end 0.2794 0.1778)
						)
						(arc
							(start 0.2794 -0.1778)
							(mid 0.249642 -0.249642)
							(end 0.1778 -0.2794)
						)
					)
					(width 0)
					(fill yes)
				)
			)
		)
		(pad "2" smd custom
			(at 0 0.4445)
			(size 0.1397 0.1397)
			(layers "F.Cu" "F.Mask" "F.Paste")
			(net "SMB_B_HUB_A0")
			(options
				(clearance outline)
				(anchor circle)
			)
			(primitives
				(gr_poly
					(pts
						(arc
							(start -0.1778 -0.2794)
							(mid -0.249642 -0.249642)
							(end -0.2794 -0.1778)
						)
						(arc
							(start -0.2794 0.1778)
							(mid -0.249642 0.249642)
							(end -0.1778 0.2794)
						)
						(arc
							(start 0.1778 0.2794)
							(mid 0.249642 0.249642)
							(end 0.2794 0.1778)
						)
						(arc
							(start 0.2794 -0.1778)
							(mid 0.249642 -0.249642)
							(end 0.1778 -0.2794)
						)
					)
					(width 0)
					(fill yes)
				)
			)
		)
	)
	(footprint ""
		(layer "F.Cu")
		(at 25.8064 -17.0434 90)
		(property "Reference" "R164"
			(at 0 0 90)
			(layer "F.SilkS")
			(hide yes)
			(effects
				(font
					(size 1.27 1.27)
				)
			)
		)
		(property "Value" "0R2F-1-GP"
			(at 0.064008 -3.993896 90)
			(unlocked yes)
			(layer "F.Fab")
			(hide yes)
			(effects
				(font
					(size 1.016 1.016)
					(thickness 0.1524)
				)
			)
		)
		(property "Device Type" "R402H16"
			(at 0.064008 -5.517896 90)
			(unlocked yes)
			(layer "F.Fab")
			(hide yes)
			(effects
				(font
					(size 1.016 1.016)
					(thickness 0.1524)
				)
			)
		)
		(duplicate_pad_numbers_are_jumpers no)
		(fp_line
			(start 0.508 -0.9398)
			(end -0.508 -0.9398)
			(stroke
				(width 0.1524)
				(type default)
			)
			(layer "F.SilkS")
		)
		(fp_line
			(start -0.508 -0.9398)
			(end -0.508 0.9398)
			(stroke
				(width 0.1524)
				(type default)
			)
			(layer "F.SilkS")
		)
		(fp_rect
			(start -0.508 0.9398)
			(end 0.508 -0.9398)
			(stroke
				(width 0)
				(type default)
			)
			(fill no)
			(layer "F.CrtYd")
		)
		(fp_rect
			(start -0.508 0.9398)
			(end 0.508 -0.9398)
			(stroke
				(width 0)
				(type default)
			)
			(fill no)
			(layer "F.Fab")
		)
		(pad "1" smd custom
			(at 0 -0.4445 90)
			(size 0.1397 0.1397)
			(layers "F.Cu" "F.Mask" "F.Paste")
			(net "SMB_VMONITOR_SLOT2_ALERT_N")
			(options
				(clearance outline)
				(anchor circle)
			)
			(primitives
				(gr_poly
					(pts
						(arc
							(start -0.1778 -0.2794)
							(mid -0.249642 -0.249642)
							(end -0.2794 -0.1778)
						)
						(arc
							(start -0.2794 0.1778)
							(mid -0.249642 0.249642)
							(end -0.1778 0.2794)
						)
						(arc
							(start 0.1778 0.2794)
							(mid 0.249642 0.249642)
							(end 0.2794 0.1778)
						)
						(arc
							(start 0.2794 -0.1778)
							(mid 0.249642 -0.249642)
							(end 0.1778 -0.2794)
						)
					)
					(width 0)
					(fill yes)
				)
			)
		)
		(pad "2" smd custom
			(at 0 0.4445 90)
			(size 0.1397 0.1397)
			(layers "F.Cu" "F.Mask" "F.Paste")
			(net "SMB_BMC_DEVICE_ALERT_N")
			(options
				(clearance outline)
				(anchor circle)
			)
			(primitives
				(gr_poly
					(pts
						(arc
							(start -0.1778 -0.2794)
							(mid -0.249642 -0.249642)
							(end -0.2794 -0.1778)
						)
						(arc
							(start -0.2794 0.1778)
							(mid -0.249642 0.249642)
							(end -0.1778 0.2794)
						)
						(arc
							(start 0.1778 0.2794)
							(mid 0.249642 0.249642)
							(end 0.2794 0.1778)
						)
						(arc
							(start 0.2794 -0.1778)
							(mid 0.249642 -0.249642)
							(end 0.1778 -0.2794)
						)
					)
					(width 0)
					(fill yes)
				)
			)
		)
	)
	(footprint ""
		(layer "F.Cu")
		(at 88.646 -18.3388 90)
		(property "Reference" "R76"
			(at 0 0 90)
			(layer "F.SilkS")
			(hide yes)
			(effects
				(font
					(size 1.27 1.27)
				)
			)
		)
		(property "Value" "0R2F-1-GP"
			(at 0.064008 -3.993896 90)
			(unlocked yes)
			(layer "F.Fab")
			(hide yes)
			(effects
				(font
					(size 1.016 1.016)
					(thickness 0.1524)
				)
			)
		)
		(property "Device Type" "R402H16"
			(at 0.064008 -5.517896 90)
			(unlocked yes)
			(layer "F.Fab")
			(hide yes)
			(effects
				(font
					(size 1.016 1.016)
					(thickness 0.1524)
				)
			)
		)
		(duplicate_pad_numbers_are_jumpers no)
		(fp_line
			(start 0.508 -0.9398)
			(end -0.508 -0.9398)
			(stroke
				(width 0.1524)
				(type default)
			)
			(layer "F.SilkS")
		)
		(fp_line
			(start -0.508 -0.9398)
			(end -0.508 0.9398)
			(stroke
				(width 0.1524)
				(type default)
			)
			(layer "F.SilkS")
		)
		(fp_rect
			(start -0.508 0.9398)
			(end 0.508 -0.9398)
			(stroke
				(width 0)
				(type default)
			)
			(fill no)
			(layer "F.CrtYd")
		)
		(fp_rect
			(start -0.508 0.9398)
			(end 0.508 -0.9398)
			(stroke
				(width 0)
				(type default)
			)
			(fill no)
			(layer "F.Fab")
		)
		(pad "1" smd custom
			(at 0 -0.4445 90)
			(size 0.1397 0.1397)
			(layers "F.Cu" "F.Mask" "F.Paste")
			(net "RESET_O_1")
			(options
				(clearance outline)
				(anchor circle)
			)
			(primitives
				(gr_poly
					(pts
						(arc
							(start -0.1778 -0.2794)
							(mid -0.249642 -0.249642)
							(end -0.2794 -0.1778)
						)
						(arc
							(start -0.2794 0.1778)
							(mid -0.249642 0.249642)
							(end -0.1778 0.2794)
						)
						(arc
							(start 0.1778 0.2794)
							(mid 0.249642 0.249642)
							(end 0.2794 0.1778)
						)
						(arc
							(start 0.2794 -0.1778)
							(mid 0.249642 -0.249642)
							(end 0.1778 -0.2794)
						)
					)
					(width 0)
					(fill yes)
				)
			)
		)
		(pad "2" smd custom
			(at 0 0.4445 90)
			(size 0.1397 0.1397)
			(layers "F.Cu" "F.Mask" "F.Paste")
			(net "PERST_N_1_R")
			(options
				(clearance outline)
				(anchor circle)
			)
			(primitives
				(gr_poly
					(pts
						(arc
							(start -0.1778 -0.2794)
							(mid -0.249642 -0.249642)
							(end -0.2794 -0.1778)
						)
						(arc
							(start -0.2794 0.1778)
							(mid -0.249642 0.249642)
							(end -0.1778 0.2794)
						)
						(arc
							(start 0.1778 0.2794)
							(mid 0.249642 0.249642)
							(end 0.2794 0.1778)
						)
						(arc
							(start 0.2794 -0.1778)
							(mid 0.249642 -0.249642)
							(end 0.1778 -0.2794)
						)
					)
					(width 0)
					(fill yes)
				)
			)
		)
	)
	(footprint ""
		(layer "F.Cu")
		(at 131.699 -15.6972 90)
		(property "Reference" "R127"
			(at 0 0 90)
			(layer "F.SilkS")
			(hide yes)
			(effects
				(font
					(size 1.27 1.27)
				)
			)
		)
		(property "Value" "10KR2F-2-GP"
			(at 0.064008 -3.993896 90)
			(unlocked yes)
			(layer "F.Fab")
			(hide yes)
			(effects
				(font
					(size 1.016 1.016)
					(thickness 0.1524)
				)
			)
		)
		(property "Device Type" "R402H16"
			(at 0.064008 -5.517896 90)
			(unlocked yes)
			(layer "F.Fab")
			(hide yes)
			(effects
				(font
					(size 1.016 1.016)
					(thickness 0.1524)
				)
			)
		)
		(duplicate_pad_numbers_are_jumpers no)
		(fp_line
			(start 0.508 -0.9398)
			(end -0.508 -0.9398)
			(stroke
				(width 0.1524)
				(type default)
			)
			(layer "F.SilkS")
		)
		(fp_line
			(start -0.508 -0.9398)
			(end -0.508 0.9398)
			(stroke
				(width 0.1524)
				(type default)
			)
			(layer "F.SilkS")
		)
		(fp_rect
			(start -0.508 0.9398)
			(end 0.508 -0.9398)
			(stroke
				(width 0)
				(type default)
			)
			(fill no)
			(layer "F.CrtYd")
		)
		(fp_rect
			(start -0.508 0.9398)
			(end 0.508 -0.9398)
			(stroke
				(width 0)
				(type default)
			)
			(fill no)
			(layer "F.Fab")
		)
		(pad "1" smd custom
			(at 0 -0.4445 90)
			(size 0.1397 0.1397)
			(layers "F.Cu" "F.Mask" "F.Paste")
			(net "GPIO_B_IO1_5")
			(options
				(clearance outline)
				(anchor circle)
			)
			(primitives
				(gr_poly
					(pts
						(arc
							(start -0.1778 -0.2794)
							(mid -0.249642 -0.249642)
							(end -0.2794 -0.1778)
						)
						(arc
							(start -0.2794 0.1778)
							(mid -0.249642 0.249642)
							(end -0.1778 0.2794)
						)
						(arc
							(start 0.1778 0.2794)
							(mid 0.249642 0.249642)
							(end 0.2794 0.1778)
						)
						(arc
							(start 0.2794 -0.1778)
							(mid 0.249642 -0.249642)
							(end 0.1778 -0.2794)
						)
					)
					(width 0)
					(fill yes)
				)
			)
		)
		(pad "2" smd custom
			(at 0 0.4445 90)
			(size 0.1397 0.1397)
			(layers "F.Cu" "F.Mask" "F.Paste")
			(net "GND")
			(options
				(clearance outline)
				(anchor circle)
			)
			(primitives
				(gr_poly
					(pts
						(arc
							(start -0.1778 -0.2794)
							(mid -0.249642 -0.249642)
							(end -0.2794 -0.1778)
						)
						(arc
							(start -0.2794 0.1778)
							(mid -0.249642 0.249642)
							(end -0.1778 0.2794)
						)
						(arc
							(start 0.1778 0.2794)
							(mid 0.249642 0.249642)
							(end 0.2794 0.1778)
						)
						(arc
							(start 0.2794 -0.1778)
							(mid 0.249642 -0.249642)
							(end 0.1778 -0.2794)
						)
					)
					(width 0)
					(fill yes)
				)
			)
		)
	)
	(footprint ""
		(layer "F.Cu")
		(at 131.699 -14.6558 -90)
		(property "Reference" "R126"
			(at 0 0 270)
			(layer "F.SilkS")
			(hide yes)
			(effects
				(font
					(size 1.27 1.27)
				)
			)
		)
		(property "Value" "10KR2F-2-GP"
			(at 0.064008 -3.993896 270)
			(unlocked yes)
			(layer "F.Fab")
			(hide yes)
			(effects
				(font
					(size 1.016 1.016)
					(thickness 0.1524)
				)
			)
		)
		(property "Device Type" "R402H16"
			(at 0.064008 -5.517896 270)
			(unlocked yes)
			(layer "F.Fab")
			(hide yes)
			(effects
				(font
					(size 1.016 1.016)
					(thickness 0.1524)
				)
			)
		)
		(duplicate_pad_numbers_are_jumpers no)
		(fp_line
			(start -0.508 -0.9398)
			(end -0.508 0.9398)
			(stroke
				(width 0.1524)
				(type default)
			)
			(layer "F.SilkS")
		)
		(fp_line
			(start 0.508 -0.9398)
			(end -0.508 -0.9398)
			(stroke
				(width 0.1524)
				(type default)
			)
			(layer "F.SilkS")
		)
		(fp_rect
			(start -0.508 0.9398)
			(end 0.508 -0.9398)
			(stroke
				(width 0)
				(type default)
			)
			(fill no)
			(layer "F.CrtYd")
		)
		(fp_rect
			(start -0.508 0.9398)
			(end 0.508 -0.9398)
			(stroke
				(width 0)
				(type default)
			)
			(fill no)
			(layer "F.Fab")
		)
		(pad "1" smd custom
			(at 0 -0.4445 270)
			(size 0.1397 0.1397)
			(layers "F.Cu" "F.Mask" "F.Paste")
			(net "P3V3_STBY")
			(options
				(clearance outline)
				(anchor circle)
			)
			(primitives
				(gr_poly
					(pts
						(arc
							(start -0.1778 -0.2794)
							(mid -0.249642 -0.249642)
							(end -0.2794 -0.1778)
						)
						(arc
							(start -0.2794 0.1778)
							(mid -0.249642 0.249642)
							(end -0.1778 0.2794)
						)
						(arc
							(start 0.1778 0.2794)
							(mid 0.249642 0.249642)
							(end 0.2794 0.1778)
						)
						(arc
							(start 0.2794 -0.1778)
							(mid 0.249642 -0.249642)
							(end 0.1778 -0.2794)
						)
					)
					(width 0)
					(fill yes)
				)
			)
		)
		(pad "2" smd custom
			(at 0 0.4445 270)
			(size 0.1397 0.1397)
			(layers "F.Cu" "F.Mask" "F.Paste")
			(net "GPIO_B_IO1_5")
			(options
				(clearance outline)
				(anchor circle)
			)
			(primitives
				(gr_poly
					(pts
						(arc
							(start -0.1778 -0.2794)
							(mid -0.249642 -0.249642)
							(end -0.2794 -0.1778)
						)
						(arc
							(start -0.2794 0.1778)
							(mid -0.249642 0.249642)
							(end -0.1778 0.2794)
						)
						(arc
							(start 0.1778 0.2794)
							(mid 0.249642 0.249642)
							(end 0.2794 0.1778)
						)
						(arc
							(start 0.2794 -0.1778)
							(mid 0.249642 -0.249642)
							(end 0.1778 -0.2794)
						)
					)
					(width 0)
					(fill yes)
				)
			)
		)
	)
	(footprint ""
		(layer "F.Cu")
		(at 113.9444 -24.0792)
		(property "Reference" "TP17"
			(at 0 0 0)
			(layer "F.SilkS")
			(hide yes)
			(effects
				(font
					(size 1.27 1.27)
				)
			)
		)
		(property "Value" "TPAD24"
			(at 0 -1.6129 0)
			(unlocked yes)
			(layer "F.Fab")
			(hide yes)
			(effects
				(font
					(size 1.016 1.016)
					(thickness 0.1524)
				)
			)
		)
		(property "Device Type" "TPAD24"
			(at 0 -3.1369 0)
			(unlocked yes)
			(layer "F.Fab")
			(hide yes)
			(effects
				(font
					(size 1.016 1.016)
					(thickness 0.1524)
				)
			)
		)
		(duplicate_pad_numbers_are_jumpers no)
		(fp_poly
			(pts
				(arc
					(start 0.3048 0)
					(mid -0.3048 0)
					(end 0.3048 0)
				)
			)
			(stroke
				(width 0)
				(type default)
			)
			(fill no)
			(layer "F.CrtYd")
		)
		(fp_poly
			(pts
				(arc
					(start 0.6096 0)
					(mid -0.6096 0)
					(end 0.6096 0)
				)
			)
			(stroke
				(width 0)
				(type default)
			)
			(fill no)
			(layer "F.Fab")
		)
		(pad "1" smd circle
			(at 0 0)
			(size 0.6096 0.6096)
			(layers "F.Cu" "F.Mask" "F.Paste")
			(net "TP_RSVD_SLOT3_PIN82")
		)
	)
	(footprint ""
		(layer "F.Cu")
		(at 119.6086 -10.2108 90)
		(property "Reference" "R134"
			(at 0 0 90)
			(layer "F.SilkS")
			(hide yes)
			(effects
				(font
					(size 1.27 1.27)
				)
			)
		)
		(property "Value" "10KR2F-2-GP"
			(at 0.064008 -3.993896 90)
			(unlocked yes)
			(layer "F.Fab")
			(hide yes)
			(effects
				(font
					(size 1.016 1.016)
					(thickness 0.1524)
				)
			)
		)
		(property "Device Type" "R402H16"
			(at 0.064008 -5.517896 90)
			(unlocked yes)
			(layer "F.Fab")
			(hide yes)
			(effects
				(font
					(size 1.016 1.016)
					(thickness 0.1524)
				)
			)
		)
		(duplicate_pad_numbers_are_jumpers no)
		(fp_line
			(start 0.508 -0.9398)
			(end -0.508 -0.9398)
			(stroke
				(width 0.1524)
				(type default)
			)
			(layer "F.SilkS")
		)
		(fp_line
			(start -0.508 -0.9398)
			(end -0.508 0.9398)
			(stroke
				(width 0.1524)
				(type default)
			)
			(layer "F.SilkS")
		)
		(fp_rect
			(start -0.508 0.9398)
			(end 0.508 -0.9398)
			(stroke
				(width 0)
				(type default)
			)
			(fill no)
			(layer "F.CrtYd")
		)
		(fp_rect
			(start -0.508 0.9398)
			(end 0.508 -0.9398)
			(stroke
				(width 0)
				(type default)
			)
			(fill no)
			(layer "F.Fab")
		)
		(pad "1" smd custom
			(at 0 -0.4445 90)
			(size 0.1397 0.1397)
			(layers "F.Cu" "F.Mask" "F.Paste")
			(net "P3V3_STBY")
			(options
				(clearance outline)
				(anchor circle)
			)
			(primitives
				(gr_poly
					(pts
						(arc
							(start -0.1778 -0.2794)
							(mid -0.249642 -0.249642)
							(end -0.2794 -0.1778)
						)
						(arc
							(start -0.2794 0.1778)
							(mid -0.249642 0.249642)
							(end -0.1778 0.2794)
						)
						(arc
							(start 0.1778 0.2794)
							(mid 0.249642 0.249642)
							(end 0.2794 0.1778)
						)
						(arc
							(start 0.2794 -0.1778)
							(mid 0.249642 -0.249642)
							(end 0.1778 -0.2794)
						)
					)
					(width 0)
					(fill yes)
				)
			)
		)
		(pad "2" smd custom
			(at 0 0.4445 90)
			(size 0.1397 0.1397)
			(layers "F.Cu" "F.Mask" "F.Paste")
			(net "GPIO_P_IO1_0")
			(options
				(clearance outline)
				(anchor circle)
			)
			(primitives
				(gr_poly
					(pts
						(arc
							(start -0.1778 -0.2794)
							(mid -0.249642 -0.249642)
							(end -0.2794 -0.1778)
						)
						(arc
							(start -0.2794 0.1778)
							(mid -0.249642 0.249642)
							(end -0.1778 0.2794)
						)
						(arc
							(start 0.1778 0.2794)
							(mid 0.249642 0.249642)
							(end 0.2794 0.1778)
						)
						(arc
							(start 0.2794 -0.1778)
							(mid 0.249642 -0.249642)
							(end 0.1778 -0.2794)
						)
					)
					(width 0)
					(fill yes)
				)
			)
		)
	)
)
